# S9S_MB_2U (Grand Teton) — schematic netlist excerpt (pin names and nets, part order shuffled) for the footprints in the layout excerpt that follows; sources: Cadence DE-HDL packaged netlist, KiCad conversion of 03242023_DA0F0TMBIJ0_F0T_Motherboard_J_brd_V01_OCP.brd

PC1339  Q_CAP  0.1UF 25V 10% X7R  pkg 0402  page 285 : A = GND ; B = PVCCIN_CPU1_VREF
R3225  Q_RES  2K 1% CHIP  pkg 0402LF  page 236 : A = SMB_S3M_CPU1_PIROM_3V3AUX_SDA ; B = P3V3_AUX

(kicad_pcb
	(version 20260206)
	(generator "pcbnew")
	(generator_version "10.0")
	(general
		(thickness 1.6)
		(legacy_teardrops no)
	)
	(paper "A4")
	(title_block
		(title "03242023_DA0F0TMBIJ0_F0T_Motherboard_J_brd_V01_OCP.brd")
		(comment 1 "Grand Teton / footprints 337-338 of 6105")
	)
	(layers
		(0 "F.Cu" signal "TOP")
		(4 "In1.Cu" signal "GND")
		(6 "In2.Cu" signal "IN1")
		(8 "In3.Cu" signal "GND1")
		(10 "In4.Cu" signal "IN2")
		(12 "In5.Cu" signal "GND2")
		(14 "In6.Cu" signal "IN3")
		(16 "In7.Cu" signal "GND3")
		(18 "In8.Cu" signal "VCC")
		(20 "In9.Cu" signal "VCC1")
		(22 "In10.Cu" signal "GND4")
		(24 "In11.Cu" signal "IN4")
		(26 "In12.Cu" signal "GND5")
		(28 "In13.Cu" signal "IN5")
		(30 "In14.Cu" signal "GND6")
		(32 "In15.Cu" signal "IN6")
		(34 "In16.Cu" signal "GND7")
		(2 "B.Cu" signal "BOTTOM")
		(9 "F.Adhes" user "F.Adhesive")
		(11 "B.Adhes" user "B.Adhesive")
		(13 "F.Paste" user "Package Geometry/Pastemask Top")
		(15 "B.Paste" user "Package Geometry/Pastemask Bottom")
		(5 "F.SilkS" user "Ref Des/Silkscreen Top")
		(7 "B.SilkS" user "Ref Des/Silkscreen Bottom")
		(1 "F.Mask" user "Board Geometry/Soldermask Top")
		(3 "B.Mask" user "Board Geometry/Soldermask Bottom")
		(17 "Dwgs.User" user "User.Drawings")
		(19 "Cmts.User" user "User.Comments")
		(21 "Eco1.User" user "User.Eco1")
		(23 "Eco2.User" user "User.Eco2")
		(25 "Edge.Cuts" user "Board Geometry/Outline")
		(27 "Margin" user)
		(31 "F.CrtYd" user "Package Geometry/Place Bound Top")
		(29 "B.CrtYd" user "Package Geometry/Place Bound Bottom")
		(35 "F.Fab" user "Ref Des/Assembly Top")
		(33 "B.Fab" user "Ref Des/Assembly Bottom")
	)
	(footprint ""
		(layer "F.Cu")
		(at 158.33471 -81.90865 -90)
		(property "Reference" "R3225"
			(at 0 0 270)
			(layer "F.SilkS")
			(hide yes)
			(effects
				(font
					(size 1.27 1.27)
				)
			)
		)
		(property "Value" ""
			(at 0 0 270)
			(layer "F.Fab")
			(effects
				(font
					(size 1.27 1.27)
				)
			)
		)
		(duplicate_pad_numbers_are_jumpers no)
		(fp_line
			(start -0.7874 0.4064)
			(end -0.7874 -0.4064)
			(stroke
				(width 0.1524)
				(type default)
			)
			(layer "F.SilkS")
		)
		(fp_line
			(start 0.7874 0.4064)
			(end -0.7874 0.4064)
			(stroke
				(width 0.1524)
				(type default)
			)
			(layer "F.SilkS")
		)
		(fp_line
			(start -0.7874 -0.4064)
			(end 0.7874 -0.4064)
			(stroke
				(width 0.1524)
				(type default)
			)
			(layer "F.SilkS")
		)
		(fp_line
			(start 0.7874 -0.4064)
			(end 0.7874 0.4064)
			(stroke
				(width 0.1524)
				(type default)
			)
			(layer "F.SilkS")
		)
		(fp_line
			(start -0.67945 0.3048)
			(end -0.67945 -0.305054)
			(stroke
				(width 0.1)
				(type default)
			)
			(layer "F.Fab")
		)
		(fp_line
			(start -0.12065 0.3048)
			(end -0.67945 0.3048)
			(stroke
				(width 0.1)
				(type default)
			)
			(layer "F.Fab")
		)
		(fp_line
			(start 0.120396 0.3048)
			(end 0.120396 0.2794)
			(stroke
				(width 0.1)
				(type default)
			)
			(layer "F.Fab")
		)
		(fp_line
			(start 0.67945 0.3048)
			(end 0.120396 0.3048)
			(stroke
				(width 0.1)
				(type default)
			)
			(layer "F.Fab")
		)
		(fp_line
			(start -0.12065 0.2794)
			(end -0.12065 0.3048)
			(stroke
				(width 0.1)
				(type default)
			)
			(layer "F.Fab")
		)
		(fp_line
			(start 0.120396 0.2794)
			(end -0.12065 0.2794)
			(stroke
				(width 0.1)
				(type default)
			)
			(layer "F.Fab")
		)
		(fp_line
			(start -0.12065 -0.2794)
			(end 0.12065 -0.2794)
			(stroke
				(width 0.1)
				(type default)
			)
			(layer "F.Fab")
		)
		(fp_line
			(start 0.12065 -0.2794)
			(end 0.12065 -0.3048)
			(stroke
				(width 0.1)
				(type default)
			)
			(layer "F.Fab")
		)
		(fp_line
			(start 0.12065 -0.3048)
			(end 0.67945 -0.3048)
			(stroke
				(width 0.1)
				(type default)
			)
			(layer "F.Fab")
		)
		(fp_line
			(start 0.67945 -0.3048)
			(end 0.67945 0.3048)
			(stroke
				(width 0.1)
				(type default)
			)
			(layer "F.Fab")
		)
		(fp_line
			(start -0.67945 -0.305054)
			(end -0.12065 -0.305054)
			(stroke
				(width 0.1)
				(type default)
			)
			(layer "F.Fab")
		)
		(fp_line
			(start -0.12065 -0.305054)
			(end -0.12065 -0.2794)
			(stroke
				(width 0.1)
				(type default)
			)
			(layer "F.Fab")
		)
		(pad "1" smd circle
			(at -0.40005 0 270)
			(size 0 0)
			(layers "F.Cu" "F.Mask" "F.Paste")
			(net "SMB_S3M_CPU1_PIROM_3V3AUX_SDA")
		)
		(pad "2" smd circle
			(at 0.40005 0 270)
			(size 0 0)
			(layers "F.Cu" "F.Mask" "F.Paste")
			(net "P3V3_AUX")
		)
	)
	(footprint ""
		(layer "F.Cu")
		(at 94.201996 -338.298282 -90)
		(property "Reference" "PC1339"
			(at 0 0 270)
			(layer "F.SilkS")
			(hide yes)
			(effects
				(font
					(size 1.27 1.27)
				)
			)
		)
		(property "Value" ""
			(at 0 0 270)
			(layer "F.Fab")
			(effects
				(font
					(size 1.27 1.27)
				)
			)
		)
		(duplicate_pad_numbers_are_jumpers no)
		(fp_line
			(start -0.7874 0.4064)
			(end -0.7874 -0.4064)
			(stroke
				(width 0.1524)
				(type default)
			)
			(layer "F.SilkS")
		)
		(fp_line
			(start 0.7874 0.4064)
			(end -0.7874 0.4064)
			(stroke
				(width 0.1524)
				(type default)
			)
			(layer "F.SilkS")
		)
		(fp_line
			(start -0.7874 -0.4064)
			(end 0.7874 -0.4064)
			(stroke
				(width 0.1524)
				(type default)
			)
			(layer "F.SilkS")
		)
		(fp_line
			(start 0.7874 -0.4064)
			(end 0.7874 0.4064)
			(stroke
				(width 0.1524)
				(type default)
			)
			(layer "F.SilkS")
		)
		(fp_line
			(start -0.67945 0.3048)
			(end -0.67945 -0.305054)
			(stroke
				(width 0.1)
				(type default)
			)
			(layer "F.Fab")
		)
		(fp_line
			(start -0.12065 0.3048)
			(end -0.67945 0.3048)
			(stroke
				(width 0.1)
				(type default)
			)
			(layer "F.Fab")
		)
		(fp_line
			(start 0.120396 0.3048)
			(end 0.120396 0.2794)
			(stroke
				(width 0.1)
				(type default)
			)
			(layer "F.Fab")
		)
		(fp_line
			(start 0.67945 0.3048)
			(end 0.120396 0.3048)
			(stroke
				(width 0.1)
				(type default)
			)
			(layer "F.Fab")
		)
		(fp_line
			(start -0.12065 0.2794)
			(end -0.12065 0.3048)
			(stroke
				(width 0.1)
				(type default)
			)
			(layer "F.Fab")
		)
		(fp_line
			(start 0.120396 0.2794)
			(end -0.12065 0.2794)
			(stroke
				(width 0.1)
				(type default)
			)
			(layer "F.Fab")
		)
		(fp_line
			(start -0.12065 -0.2794)
			(end 0.12065 -0.2794)
			(stroke
				(width 0.1)
				(type default)
			)
			(layer "F.Fab")
		)
		(fp_line
			(start 0.12065 -0.2794)
			(end 0.12065 -0.3048)
			(stroke
				(width 0.1)
				(type default)
			)
			(layer "F.Fab")
		)
		(fp_line
			(start 0.12065 -0.3048)
			(end 0.67945 -0.3048)
			(stroke
				(width 0.1)
				(type default)
			)
			(layer "F.Fab")
		)
		(fp_line
			(start 0.67945 -0.3048)
			(end 0.67945 0.3048)
			(stroke
				(width 0.1)
				(type default)
			)
			(layer "F.Fab")
		)
		(fp_line
			(start -0.67945 -0.305054)
			(end -0.12065 -0.305054)
			(stroke
				(width 0.1)
				(type default)
			)
			(layer "F.Fab")
		)
		(fp_line
			(start -0.12065 -0.305054)
			(end -0.12065 -0.2794)
			(stroke
				(width 0.1)
				(type default)
			)
			(layer "F.Fab")
		)
		(pad "1" smd circle
			(at -0.40005 0 270)
			(size 0 0)
			(layers "F.Cu" "F.Mask" "F.Paste")
			(net "GND")
		)
		(pad "2" smd circle
			(at 0.40005 0 270)
			(size 0 0)
			(layers "F.Cu" "F.Mask" "F.Paste")
			(net "PVCCIN_CPU1_VREF")
		)
	)
)
